(kicad_pcb
	(version 20260206)
	(generator "pcbnew")
	(generator_version "10.0")
	(general
		(thickness 1.6)
		(legacy_teardrops no)
	)
	(paper "A4")
	(title_block
		(title "Bryce Canyon_R.DPB_16317-1_OCP.brd")
		(comment 1 "Bryce Canyon / footprints 1720-1728 of 2099")
	)
	(layers
		(0 "F.Cu" signal "TOP")
		(4 "In1.Cu" signal "L2GND")
		(6 "In2.Cu" signal "L3")
		(8 "In3.Cu" signal "L4VCC")
		(10 "In4.Cu" signal "L5VCC")
		(12 "In5.Cu" signal "L6")
		(14 "In6.Cu" signal "L7GND")
		(2 "B.Cu" signal "BOTTOM")
		(9 "F.Adhes" user "F.Adhesive")
		(11 "B.Adhes" user "B.Adhesive")
		(13 "F.Paste" user "Package Geometry/Pastemask Top")
		(15 "B.Paste" user "Package Geometry/Pastemask Bottom")
		(5 "F.SilkS" user "Ref Des/Silkscreen Top")
		(7 "B.SilkS" user "Ref Des/Silkscreen Bottom")
		(1 "F.Mask" user "Board Geometry/Soldermask Top")
		(3 "B.Mask" user "Board Geometry/Soldermask Bottom")
		(17 "Dwgs.User" user "User.Drawings")
		(19 "Cmts.User" user "User.Comments")
		(21 "Eco1.User" user "User.Eco1")
		(23 "Eco2.User" user "User.Eco2")
		(25 "Edge.Cuts" user "Board Geometry/Outline")
		(27 "Margin" user)
		(31 "F.CrtYd" user "Package Geometry/Place Bound Top")
		(29 "B.CrtYd" user "Package Geometry/Place Bound Bottom")
		(35 "F.Fab" user "Ref Des/Assembly Top")
		(33 "B.Fab" user "Ref Des/Assembly Bottom")
	)
	(footprint ""
		(layer "F.Cu")
		(at 165.42893 -362.691426 180)
		(property "Reference" "C550"
			(at 0 0 180)
			(layer "F.SilkS")
			(hide yes)
			(effects
				(font
					(size 1.27 1.27)
				)
			)
		)
		(property "Value" "SC1U16V3KX-5GP"
			(at 0 -2.8194 180)
			(unlocked yes)
			(layer "F.Fab")
			(hide yes)
			(effects
				(font
					(size 1.016 1.016)
					(thickness 0.1524)
				)
			)
		)
		(property "Device Type" "C603H36"
			(at 0 -4.3434 180)
			(unlocked yes)
			(layer "F.Fab")
			(hide yes)
			(effects
				(font
					(size 1.016 1.016)
					(thickness 0.1524)
				)
			)
		)
		(duplicate_pad_numbers_are_jumpers no)
		(fp_line
			(start 0.508 0)
			(end -0.508 0)
			(stroke
				(width 0.2032)
				(type default)
			)
			(layer "F.SilkS")
		)
		(fp_rect
			(start -0.5842 1.3335)
			(end 0.5842 -1.3335)
			(stroke
				(width 0)
				(type default)
			)
			(fill no)
			(layer "F.CrtYd")
		)
		(fp_rect
			(start -0.5842 1.3335)
			(end 0.5842 -1.3335)
			(stroke
				(width 0)
				(type default)
			)
			(fill no)
			(layer "F.Fab")
		)
		(pad "1" smd custom
			(at 0 -0.762 180)
			(size 0.2159 0.2159)
			(layers "F.Cu" "F.Mask" "F.Paste")
			(net "MB0_CM_OV_R")
			(options
				(clearance outline)
				(anchor circle)
			)
			(primitives
				(gr_poly
					(pts
						(arc
							(start -0.3302 -0.4318)
							(mid -0.402042 -0.402042)
							(end -0.4318 -0.3302)
						)
						(arc
							(start -0.4318 0.3302)
							(mid -0.402042 0.402042)
							(end -0.3302 0.4318)
						)
						(arc
							(start 0.3302 0.4318)
							(mid 0.402042 0.402042)
							(end 0.4318 0.3302)
						)
						(arc
							(start 0.4318 -0.3302)
							(mid 0.402042 -0.402042)
							(end 0.3302 -0.4318)
						)
					)
					(width 0)
					(fill yes)
				)
			)
		)
		(pad "2" smd custom
			(at 0 0.762 180)
			(size 0.2159 0.2159)
			(layers "F.Cu" "F.Mask" "F.Paste")
			(net "AGND_CURRENT_MON")
			(options
				(clearance outline)
				(anchor circle)
			)
			(primitives
				(gr_poly
					(pts
						(arc
							(start -0.3302 -0.4318)
							(mid -0.402042 -0.402042)
							(end -0.4318 -0.3302)
						)
						(arc
							(start -0.4318 0.3302)
							(mid -0.402042 0.402042)
							(end -0.3302 0.4318)
						)
						(arc
							(start 0.3302 0.4318)
							(mid 0.402042 0.402042)
							(end 0.4318 0.3302)
						)
						(arc
							(start 0.4318 -0.3302)
							(mid 0.402042 -0.402042)
							(end 0.3302 -0.4318)
						)
					)
					(width 0)
					(fill yes)
				)
			)
		)
	)
	(footprint ""
		(layer "F.Cu")
		(at 222.123 -207.01 90)
		(property "Reference" "R52"
			(at 0 0 90)
			(layer "F.SilkS")
			(hide yes)
			(effects
				(font
					(size 1.27 1.27)
				)
			)
		)
		(property "Value" "4K7R2F-GP"
			(at 0.064008 -3.993896 90)
			(unlocked yes)
			(layer "F.Fab")
			(hide yes)
			(effects
				(font
					(size 1.016 1.016)
					(thickness 0.1524)
				)
			)
		)
		(property "Device Type" "R402H16"
			(at 0.064008 -5.517896 90)
			(unlocked yes)
			(layer "F.Fab")
			(hide yes)
			(effects
				(font
					(size 1.016 1.016)
					(thickness 0.1524)
				)
			)
		)
		(duplicate_pad_numbers_are_jumpers no)
		(fp_line
			(start 0.508 -0.9398)
			(end -0.508 -0.9398)
			(stroke
				(width 0.1524)
				(type default)
			)
			(layer "F.SilkS")
		)
		(fp_line
			(start -0.508 -0.9398)
			(end -0.508 0.9398)
			(stroke
				(width 0.1524)
				(type default)
			)
			(layer "F.SilkS")
		)
		(fp_rect
			(start -0.508 0.9398)
			(end 0.508 -0.9398)
			(stroke
				(width 0)
				(type default)
			)
			(fill no)
			(layer "F.CrtYd")
		)
		(fp_rect
			(start -0.508 0.9398)
			(end 0.508 -0.9398)
			(stroke
				(width 0)
				(type default)
			)
			(fill no)
			(layer "F.Fab")
		)
		(pad "1" smd custom
			(at 0 -0.4445 90)
			(size 0.1397 0.1397)
			(layers "F.Cu" "F.Mask" "F.Paste")
			(net "IO_EXP5_A2")
			(options
				(clearance outline)
				(anchor circle)
			)
			(primitives
				(gr_poly
					(pts
						(arc
							(start -0.1778 -0.2794)
							(mid -0.249642 -0.249642)
							(end -0.2794 -0.1778)
						)
						(arc
							(start -0.2794 0.1778)
							(mid -0.249642 0.249642)
							(end -0.1778 0.2794)
						)
						(arc
							(start 0.1778 0.2794)
							(mid 0.249642 0.249642)
							(end 0.2794 0.1778)
						)
						(arc
							(start 0.2794 -0.1778)
							(mid 0.249642 -0.249642)
							(end 0.1778 -0.2794)
						)
					)
					(width 0)
					(fill yes)
				)
			)
		)
		(pad "2" smd custom
			(at 0 0.4445 90)
			(size 0.1397 0.1397)
			(layers "F.Cu" "F.Mask" "F.Paste")
			(net "GND")
			(options
				(clearance outline)
				(anchor circle)
			)
			(primitives
				(gr_poly
					(pts
						(arc
							(start -0.1778 -0.2794)
							(mid -0.249642 -0.249642)
							(end -0.2794 -0.1778)
						)
						(arc
							(start -0.2794 0.1778)
							(mid -0.249642 0.249642)
							(end -0.1778 0.2794)
						)
						(arc
							(start 0.1778 0.2794)
							(mid 0.249642 0.249642)
							(end 0.2794 0.1778)
						)
						(arc
							(start 0.2794 -0.1778)
							(mid 0.249642 -0.249642)
							(end 0.1778 -0.2794)
						)
					)
					(width 0)
					(fill yes)
				)
			)
		)
	)
	(footprint ""
		(layer "F.Cu")
		(at 160.963864 -39.705026)
		(property "Reference" "TP161"
			(at 0 0 0)
			(layer "F.SilkS")
			(hide yes)
			(effects
				(font
					(size 1.27 1.27)
				)
			)
		)
		(property "Value" "*"
			(at -0.0508 -1.6764 0)
			(unlocked yes)
			(layer "F.Fab")
			(hide yes)
			(effects
				(font
					(size 1.016 1.016)
					(thickness 0.1524)
				)
			)
		)
		(property "Device Type" "TPAD32"
			(at -0.0508 -3.2004 0)
			(unlocked yes)
			(layer "F.Fab")
			(hide yes)
			(effects
				(font
					(size 1.016 1.016)
					(thickness 0.1524)
				)
			)
		)
		(duplicate_pad_numbers_are_jumpers no)
		(fp_poly
			(pts
				(arc
					(start 0.4064 0)
					(mid -0.4064 0)
					(end 0.4064 0)
				)
			)
			(stroke
				(width 0)
				(type default)
			)
			(fill no)
			(layer "F.CrtYd")
		)
		(fp_poly
			(pts
				(arc
					(start 0.7112 0)
					(mid -0.7112 0)
					(end 0.7112 0)
				)
			)
			(stroke
				(width 0)
				(type default)
			)
			(fill no)
			(layer "F.Fab")
		)
		(pad "1" smd circle
			(at 0 0)
			(size 0.8128 0.8128)
			(layers "F.Cu" "F.Mask" "F.Paste")
			(net "ACT_HDD_28")
		)
	)
	(footprint ""
		(layer "F.Cu")
		(at 361.315 -160.401 180)
		(property "Reference" "C284"
			(at 0 0 180)
			(layer "F.SilkS")
			(hide yes)
			(effects
				(font
					(size 1.27 1.27)
				)
			)
		)
		(property "Value" "SC1U25V3KX-GP"
			(at 0 -2.8194 180)
			(unlocked yes)
			(layer "F.Fab")
			(hide yes)
			(effects
				(font
					(size 1.016 1.016)
					(thickness 0.1524)
				)
			)
		)
		(property "Device Type" "C603H36"
			(at 0 -4.3434 180)
			(unlocked yes)
			(layer "F.Fab")
			(hide yes)
			(effects
				(font
					(size 1.016 1.016)
					(thickness 0.1524)
				)
			)
		)
		(duplicate_pad_numbers_are_jumpers no)
		(fp_line
			(start 0.508 0)
			(end -0.508 0)
			(stroke
				(width 0.2032)
				(type default)
			)
			(layer "F.SilkS")
		)
		(fp_rect
			(start -0.5842 1.3335)
			(end 0.5842 -1.3335)
			(stroke
				(width 0)
				(type default)
			)
			(fill no)
			(layer "F.CrtYd")
		)
		(fp_rect
			(start -0.5842 1.3335)
			(end 0.5842 -1.3335)
			(stroke
				(width 0)
				(type default)
			)
			(fill no)
			(layer "F.Fab")
		)
		(pad "1" smd custom
			(at 0 -0.762 180)
			(size 0.2159 0.2159)
			(layers "F.Cu" "F.Mask" "F.Paste")
			(net "P12V_HDD19")
			(options
				(clearance outline)
				(anchor circle)
			)
			(primitives
				(gr_poly
					(pts
						(arc
							(start -0.3302 -0.4318)
							(mid -0.402042 -0.402042)
							(end -0.4318 -0.3302)
						)
						(arc
							(start -0.4318 0.3302)
							(mid -0.402042 0.402042)
							(end -0.3302 0.4318)
						)
						(arc
							(start 0.3302 0.4318)
							(mid 0.402042 0.402042)
							(end 0.4318 0.3302)
						)
						(arc
							(start 0.4318 -0.3302)
							(mid 0.402042 -0.402042)
							(end 0.3302 -0.4318)
						)
					)
					(width 0)
					(fill yes)
				)
			)
		)
		(pad "2" smd custom
			(at 0 0.762 180)
			(size 0.2159 0.2159)
			(layers "F.Cu" "F.Mask" "F.Paste")
			(net "GND")
			(options
				(clearance outline)
				(anchor circle)
			)
			(primitives
				(gr_poly
					(pts
						(arc
							(start -0.3302 -0.4318)
							(mid -0.402042 -0.402042)
							(end -0.4318 -0.3302)
						)
						(arc
							(start -0.4318 0.3302)
							(mid -0.402042 0.402042)
							(end -0.3302 0.4318)
						)
						(arc
							(start 0.3302 0.4318)
							(mid 0.402042 0.402042)
							(end 0.4318 0.3302)
						)
						(arc
							(start 0.4318 -0.3302)
							(mid 0.402042 -0.402042)
							(end 0.3302 -0.4318)
						)
					)
					(width 0)
					(fill yes)
				)
			)
		)
	)
	(footprint ""
		(layer "F.Cu")
		(at 280.444448 -355.415342 -90)
		(property "Reference" "R1075"
			(at 0 0 270)
			(layer "F.SilkS")
			(hide yes)
			(effects
				(font
					(size 1.27 1.27)
				)
			)
		)
		(property "Value" "0R2J-2-GP"
			(at 0.064008 -3.993896 270)
			(unlocked yes)
			(layer "F.Fab")
			(hide yes)
			(effects
				(font
					(size 1.016 1.016)
					(thickness 0.1524)
				)
			)
		)
		(property "Device Type" "R402H16"
			(at 0.064008 -5.517896 270)
			(unlocked yes)
			(layer "F.Fab")
			(hide yes)
			(effects
				(font
					(size 1.016 1.016)
					(thickness 0.1524)
				)
			)
		)
		(duplicate_pad_numbers_are_jumpers no)
		(fp_line
			(start -0.508 -0.9398)
			(end -0.508 0.9398)
			(stroke
				(width 0.1524)
				(type default)
			)
			(layer "F.SilkS")
		)
		(fp_line
			(start 0.508 -0.9398)
			(end -0.508 -0.9398)
			(stroke
				(width 0.1524)
				(type default)
			)
			(layer "F.SilkS")
		)
		(fp_rect
			(start -0.508 0.9398)
			(end 0.508 -0.9398)
			(stroke
				(width 0)
				(type default)
			)
			(fill no)
			(layer "F.CrtYd")
		)
		(fp_rect
			(start -0.508 0.9398)
			(end 0.508 -0.9398)
			(stroke
				(width 0)
				(type default)
			)
			(fill no)
			(layer "F.Fab")
		)
		(pad "1" smd custom
			(at 0 -0.4445 270)
			(size 0.1397 0.1397)
			(layers "F.Cu" "F.Mask" "F.Paste")
			(net "MAX31790_B_SDA")
			(options
				(clearance outline)
				(anchor circle)
			)
			(primitives
				(gr_poly
					(pts
						(arc
							(start -0.1778 -0.2794)
							(mid -0.249642 -0.249642)
							(end -0.2794 -0.1778)
						)
						(arc
							(start -0.2794 0.1778)
							(mid -0.249642 0.249642)
							(end -0.1778 0.2794)
						)
						(arc
							(start 0.1778 0.2794)
							(mid 0.249642 0.249642)
							(end 0.2794 0.1778)
						)
						(arc
							(start 0.2794 -0.1778)
							(mid 0.249642 -0.249642)
							(end 0.1778 -0.2794)
						)
					)
					(width 0)
					(fill yes)
				)
			)
		)
		(pad "2" smd custom
			(at 0 0.4445 270)
			(size 0.1397 0.1397)
			(layers "F.Cu" "F.Mask" "F.Paste")
			(net "I2C_DPB_B_SDA_BUF")
			(options
				(clearance outline)
				(anchor circle)
			)
			(primitives
				(gr_poly
					(pts
						(arc
							(start -0.1778 -0.2794)
							(mid -0.249642 -0.249642)
							(end -0.2794 -0.1778)
						)
						(arc
							(start -0.2794 0.1778)
							(mid -0.249642 0.249642)
							(end -0.1778 0.2794)
						)
						(arc
							(start 0.1778 0.2794)
							(mid 0.249642 0.249642)
							(end 0.2794 0.1778)
						)
						(arc
							(start 0.2794 -0.1778)
							(mid 0.249642 -0.249642)
							(end 0.1778 -0.2794)
						)
					)
					(width 0)
					(fill yes)
				)
			)
		)
	)
	(footprint ""
		(layer "F.Cu")
		(at 86.995 -272.288)
		(property "Reference" "C61"
			(at 0 0 0)
			(layer "F.SilkS")
			(hide yes)
			(effects
				(font
					(size 1.27 1.27)
				)
			)
		)
		(property "Value" "SC4D7U25V5KX-1-GP"
			(at -0.0762 -6.1214 0)
			(unlocked yes)
			(layer "F.Fab")
			(hide yes)
			(effects
				(font
					(size 1.016 1.016)
					(thickness 0.1524)
				)
			)
		)
		(property "Device Type" "C805H58"
			(at -0.0762 -8.1534 0)
			(unlocked yes)
			(layer "F.Fab")
			(hide yes)
			(effects
				(font
					(size 1.016 1.016)
					(thickness 0.1524)
				)
			)
		)
		(duplicate_pad_numbers_are_jumpers no)
		(fp_line
			(start 0.635 0)
			(end -0.635 0)
			(stroke
				(width 0.508)
				(type default)
			)
			(layer "F.SilkS")
		)
		(fp_rect
			(start -0.9652 1.778)
			(end 0.9652 -1.778)
			(stroke
				(width 0)
				(type default)
			)
			(fill no)
			(layer "F.CrtYd")
		)
		(fp_poly
			(pts
				(xy -0.9652 -1.778) (xy 0.9652 -1.778) (xy 0.9652 1.778) (xy -0.9652 1.778)
			)
			(stroke
				(width 0)
				(type default)
			)
			(fill no)
			(layer "F.Fab")
		)
		(pad "1" smd rect
			(at 0 -0.9652)
			(size 1.397 1.143)
			(layers "F.Cu" "F.Mask" "F.Paste")
			(net "P12V_HDD2")
		)
		(pad "2" smd rect
			(at 0 0.9652)
			(size 1.397 1.143)
			(layers "F.Cu" "F.Mask" "F.Paste")
			(net "GND")
		)
	)
	(footprint ""
		(layer "F.Cu")
		(at 426.879004 -364.998)
		(property "Reference" "C538"
			(at 0 0 0)
			(layer "F.SilkS")
			(hide yes)
			(effects
				(font
					(size 1.27 1.27)
				)
			)
		)
		(property "Value" "SCD1U25V2KX-2-GP"
			(at 1.1811 -2.7051 0)
			(unlocked yes)
			(layer "F.Fab")
			(hide yes)
			(effects
				(font
					(size 1.016 1.016)
					(thickness 0.1524)
				)
			)
		)
		(property "Device Type" "C402H22"
			(at 1.1811 -4.2291 0)
			(unlocked yes)
			(layer "F.Fab")
			(hide yes)
			(effects
				(font
					(size 1.016 1.016)
					(thickness 0.1524)
				)
			)
		)
		(duplicate_pad_numbers_are_jumpers no)
		(fp_rect
			(start -0.4318 0.9525)
			(end 0.4318 -0.9525)
			(stroke
				(width 0)
				(type default)
			)
			(fill no)
			(layer "F.CrtYd")
		)
		(fp_rect
			(start -0.4318 0.9525)
			(end 0.4318 -0.9525)
			(stroke
				(width 0)
				(type default)
			)
			(fill no)
			(layer "F.Fab")
		)
		(pad "1" smd custom
			(at 0 -0.4445)
			(size 0.1524 0.1524)
			(layers "F.Cu" "F.Mask" "F.Paste")
			(net "FAN_3_TACH1")
			(options
				(clearance outline)
				(anchor circle)
			)
			(primitives
				(gr_poly
					(pts
						(arc
							(start 0.3048 -0.2032)
							(mid 0.275042 -0.275042)
							(end 0.2032 -0.3048)
						)
						(arc
							(start -0.2032 -0.3048)
							(mid -0.275042 -0.275042)
							(end -0.3048 -0.2032)
						)
						(arc
							(start -0.3048 0.2032)
							(mid -0.275042 0.275042)
							(end -0.2032 0.3048)
						)
						(arc
							(start 0.2032 0.3048)
							(mid 0.275042 0.275042)
							(end 0.3048 0.2032)
						)
					)
					(width 0)
					(fill yes)
				)
			)
		)
		(pad "2" smd custom
			(at 0 0.4445)
			(size 0.1524 0.1524)
			(layers "F.Cu" "F.Mask" "F.Paste")
			(net "GND")
			(options
				(clearance outline)
				(anchor circle)
			)
			(primitives
				(gr_poly
					(pts
						(arc
							(start 0.3048 -0.2032)
							(mid 0.275042 -0.275042)
							(end 0.2032 -0.3048)
						)
						(arc
							(start -0.2032 -0.3048)
							(mid -0.275042 -0.275042)
							(end -0.3048 -0.2032)
						)
						(arc
							(start -0.3048 0.2032)
							(mid -0.275042 0.275042)
							(end -0.2032 0.3048)
						)
						(arc
							(start 0.2032 0.3048)
							(mid 0.275042 0.275042)
							(end 0.3048 0.2032)
						)
					)
					(width 0)
					(fill yes)
				)
			)
		)
	)
	(footprint ""
		(layer "F.Cu")
		(at 332.359 -266.827 180)
		(property "Reference" "C109"
			(at 0 0 180)
			(layer "F.SilkS")
			(hide yes)
			(effects
				(font
					(size 1.27 1.27)
				)
			)
		)
		(property "Value" "SC10U16V6KX-2GP"
			(at -0.0762 -5.1308 180)
			(unlocked yes)
			(layer "F.Fab")
			(hide yes)
			(effects
				(font
					(size 1.016 1.016)
					(thickness 0.1524)
				)
			)
		)
		(property "Device Type" "C1206H71"
			(at -0.127 -6.6548 180)
			(unlocked yes)
			(layer "F.Fab")
			(hide yes)
			(effects
				(font
					(size 1.016 1.016)
					(thickness 0.1524)
				)
			)
		)
		(duplicate_pad_numbers_are_jumpers no)
		(fp_line
			(start 1.016 2.2352)
			(end -1.016 2.2352)
			(stroke
				(width 0.1524)
				(type default)
			)
			(layer "F.SilkS")
		)
		(fp_line
			(start 1.016 0.8382)
			(end 1.016 2.2352)
			(stroke
				(width 0.1524)
				(type default)
			)
			(layer "F.SilkS")
		)
		(fp_line
			(start 1.016 -2.2352)
			(end 1.016 -0.8382)
			(stroke
				(width 0.1524)
				(type default)
			)
			(layer "F.SilkS")
		)
		(fp_line
			(start -1.016 2.2352)
			(end -1.016 0.8382)
			(stroke
				(width 0.1524)
				(type default)
			)
			(layer "F.SilkS")
		)
		(fp_line
			(start -1.016 -0.8382)
			(end -1.016 -2.2352)
			(stroke
				(width 0.1524)
				(type default)
			)
			(layer "F.SilkS")
		)
		(fp_line
			(start -1.016 -2.2352)
			(end 1.016 -2.2352)
			(stroke
				(width 0.1524)
				(type default)
			)
			(layer "F.SilkS")
		)
		(fp_rect
			(start -1.0922 2.3114)
			(end 1.0922 -2.3114)
			(stroke
				(width 0)
				(type default)
			)
			(fill no)
			(layer "F.CrtYd")
		)
		(fp_poly
			(pts
				(xy 1.0922 -2.3114) (xy 1.0922 2.3114) (xy -1.0922 2.3114) (xy -1.0922 -2.3114)
			)
			(stroke
				(width 0)
				(type default)
			)
			(fill no)
			(layer "F.Fab")
		)
		(pad "1" smd rect
			(at 0 -1.397 180)
			(size 1.651 1.27)
			(layers "F.Cu" "F.Mask" "F.Paste")
			(net "P5V_HDD6")
		)
		(pad "2" smd rect
			(at 0 1.397 180)
			(size 1.651 1.27)
			(layers "F.Cu" "F.Mask" "F.Paste")
			(net "GND")
		)
	)
	(footprint ""
		(layer "F.Cu")
		(at 46.482 -255.524 90)
		(property "Reference" "C52"
			(at 0 0 90)
			(layer "F.SilkS")
			(hide yes)
			(effects
				(font
					(size 1.27 1.27)
				)
			)
		)
		(property "Value" "SCD033U25V2KX-GP"
			(at 1.1811 -2.7051 90)
			(unlocked yes)
			(layer "F.Fab")
			(hide yes)
			(effects
				(font
					(size 1.016 1.016)
					(thickness 0.1524)
				)
			)
		)
		(property "Device Type" "C402H22"
			(at 1.1811 -4.2291 90)
			(unlocked yes)
			(layer "F.Fab")
			(hide yes)
			(effects
				(font
					(size 1.016 1.016)
					(thickness 0.1524)
				)
			)
		)
		(duplicate_pad_numbers_are_jumpers no)
		(fp_rect
			(start -0.4318 0.9525)
			(end 0.4318 -0.9525)
			(stroke
				(width 0)
				(type default)
			)
			(fill no)
			(layer "F.CrtYd")
		)
		(fp_rect
			(start -0.4318 0.9525)
			(end 0.4318 -0.9525)
			(stroke
				(width 0)
				(type default)
			)
			(fill no)
			(layer "F.Fab")
		)
		(pad "1" smd custom
			(at 0 -0.4445 90)
			(size 0.1524 0.1524)
			(layers "F.Cu" "F.Mask" "F.Paste")
			(net "P12V_B")
			(options
				(clearance outline)
				(anchor circle)
			)
			(primitives
				(gr_poly
					(pts
						(arc
							(start 0.3048 -0.2032)
							(mid 0.275042 -0.275042)
							(end 0.2032 -0.3048)
						)
						(arc
							(start -0.2032 -0.3048)
							(mid -0.275042 -0.275042)
							(end -0.3048 -0.2032)
						)
						(arc
							(start -0.3048 0.2032)
							(mid -0.275042 0.275042)
							(end -0.2032 0.3048)
						)
						(arc
							(start 0.2032 0.3048)
							(mid 0.275042 0.275042)
							(end 0.3048 0.2032)
						)
					)
					(width 0)
					(fill yes)
				)
			)
		)
		(pad "2" smd custom
			(at 0 0.4445 90)
			(size 0.1524 0.1524)
			(layers "F.Cu" "F.Mask" "F.Paste")
			(net "SW_HDD_N1")
			(options
				(clearance outline)
				(anchor circle)
			)
			(primitives
				(gr_poly
					(pts
						(arc
							(start 0.3048 -0.2032)
							(mid 0.275042 -0.275042)
							(end 0.2032 -0.3048)
						)
						(arc
							(start -0.2032 -0.3048)
							(mid -0.275042 -0.275042)
							(end -0.3048 -0.2032)
						)
						(arc
							(start -0.3048 0.2032)
							(mid -0.275042 0.275042)
							(end -0.2032 0.3048)
						)
						(arc
							(start 0.2032 0.3048)
							(mid 0.275042 0.275042)
							(end 0.3048 0.2032)
						)
					)
					(width 0)
					(fill yes)
				)
			)
		)
	)
)
